# S9S_MB_2U (Grand Teton) — schematic netlist excerpt (pin names and nets, part order shuffled) for the footprints in the layout excerpt that follows; sources: Cadence DE-HDL packaged netlist, KiCad conversion of 03242023_DA0F0TMBIJ0_F0T_Motherboard_J_brd_V01_OCP.brd

R3588  Q_RES  33.2 1% CHIP  pkg 0402LF  page 232 : A = SMB_INA230_3V3AUX_SCL ; B = SMB_INA230_2_3V3AUX_SCL_R
R2209  Q_RES  0 5% CHIP  pkg 0402LF  page 236 : A = SMB_S3M_CPU0_3V3AUX_SCL_R ; B = SMB_S3M_CPU0_3V3AUX_SCL

(kicad_pcb
	(version 20260206)
	(generator "pcbnew")
	(generator_version "10.0")
	(general
		(thickness 1.6)
		(legacy_teardrops no)
	)
	(paper "A4")
	(title_block
		(title "03242023_DA0F0TMBIJ0_F0T_Motherboard_J_brd_V01_OCP.brd")
		(comment 1 "Grand Teton / footprints 2386-2387 of 6105")
	)
	(layers
		(0 "F.Cu" signal "TOP")
		(4 "In1.Cu" signal "GND")
		(6 "In2.Cu" signal "IN1")
		(8 "In3.Cu" signal "GND1")
		(10 "In4.Cu" signal "IN2")
		(12 "In5.Cu" signal "GND2")
		(14 "In6.Cu" signal "IN3")
		(16 "In7.Cu" signal "GND3")
		(18 "In8.Cu" signal "VCC")
		(20 "In9.Cu" signal "VCC1")
		(22 "In10.Cu" signal "GND4")
		(24 "In11.Cu" signal "IN4")
		(26 "In12.Cu" signal "GND5")
		(28 "In13.Cu" signal "IN5")
		(30 "In14.Cu" signal "GND6")
		(32 "In15.Cu" signal "IN6")
		(34 "In16.Cu" signal "GND7")
		(2 "B.Cu" signal "BOTTOM")
		(9 "F.Adhes" user "F.Adhesive")
		(11 "B.Adhes" user "B.Adhesive")
		(13 "F.Paste" user "Package Geometry/Pastemask Top")
		(15 "B.Paste" user "Package Geometry/Pastemask Bottom")
		(5 "F.SilkS" user "Ref Des/Silkscreen Top")
		(7 "B.SilkS" user "Ref Des/Silkscreen Bottom")
		(1 "F.Mask" user "Board Geometry/Soldermask Top")
		(3 "B.Mask" user "Board Geometry/Soldermask Bottom")
		(17 "Dwgs.User" user "User.Drawings")
		(19 "Cmts.User" user "User.Comments")
		(21 "Eco1.User" user "User.Eco1")
		(23 "Eco2.User" user "User.Eco2")
		(25 "Edge.Cuts" user "Board Geometry/Outline")
		(27 "Margin" user)
		(31 "F.CrtYd" user "Package Geometry/Place Bound Top")
		(29 "B.CrtYd" user "Package Geometry/Place Bound Bottom")
		(35 "F.Fab" user "Ref Des/Assembly Top")
		(33 "B.Fab" user "Ref Des/Assembly Bottom")
	)
	(footprint ""
		(layer "F.Cu")
		(at 162.34283 -76.770738)
		(property "Reference" "R2209"
			(at 0 0 0)
			(layer "F.SilkS")
			(hide yes)
			(effects
				(font
					(size 1.27 1.27)
				)
			)
		)
		(property "Value" ""
			(at 0 0 0)
			(layer "F.Fab")
			(effects
				(font
					(size 1.27 1.27)
				)
			)
		)
		(duplicate_pad_numbers_are_jumpers no)
		(fp_line
			(start -0.7874 -0.4064)
			(end 0.7874 -0.4064)
			(stroke
				(width 0.1524)
				(type default)
			)
			(layer "F.SilkS")
		)
		(fp_line
			(start -0.7874 0.4064)
			(end -0.7874 -0.4064)
			(stroke
				(width 0.1524)
				(type default)
			)
			(layer "F.SilkS")
		)
		(fp_line
			(start 0.7874 -0.4064)
			(end 0.7874 0.4064)
			(stroke
				(width 0.1524)
				(type default)
			)
			(layer "F.SilkS")
		)
		(fp_line
			(start 0.7874 0.4064)
			(end -0.7874 0.4064)
			(stroke
				(width 0.1524)
				(type default)
			)
			(layer "F.SilkS")
		)
		(fp_line
			(start -0.67945 -0.305054)
			(end -0.12065 -0.305054)
			(stroke
				(width 0.1)
				(type default)
			)
			(layer "F.Fab")
		)
		(fp_line
			(start -0.67945 0.3048)
			(end -0.67945 -0.305054)
			(stroke
				(width 0.1)
				(type default)
			)
			(layer "F.Fab")
		)
		(fp_line
			(start -0.12065 -0.305054)
			(end -0.12065 -0.2794)
			(stroke
				(width 0.1)
				(type default)
			)
			(layer "F.Fab")
		)
		(fp_line
			(start -0.12065 -0.2794)
			(end 0.12065 -0.2794)
			(stroke
				(width 0.1)
				(type default)
			)
			(layer "F.Fab")
		)
		(fp_line
			(start -0.12065 0.2794)
			(end -0.12065 0.3048)
			(stroke
				(width 0.1)
				(type default)
			)
			(layer "F.Fab")
		)
		(fp_line
			(start -0.12065 0.3048)
			(end -0.67945 0.3048)
			(stroke
				(width 0.1)
				(type default)
			)
			(layer "F.Fab")
		)
		(fp_line
			(start 0.120396 0.2794)
			(end -0.12065 0.2794)
			(stroke
				(width 0.1)
				(type default)
			)
			(layer "F.Fab")
		)
		(fp_line
			(start 0.120396 0.3048)
			(end 0.120396 0.2794)
			(stroke
				(width 0.1)
				(type default)
			)
			(layer "F.Fab")
		)
		(fp_line
			(start 0.12065 -0.3048)
			(end 0.67945 -0.3048)
			(stroke
				(width 0.1)
				(type default)
			)
			(layer "F.Fab")
		)
		(fp_line
			(start 0.12065 -0.2794)
			(end 0.12065 -0.3048)
			(stroke
				(width 0.1)
				(type default)
			)
			(layer "F.Fab")
		)
		(fp_line
			(start 0.67945 -0.3048)
			(end 0.67945 0.3048)
			(stroke
				(width 0.1)
				(type default)
			)
			(layer "F.Fab")
		)
		(fp_line
			(start 0.67945 0.3048)
			(end 0.120396 0.3048)
			(stroke
				(width 0.1)
				(type default)
			)
			(layer "F.Fab")
		)
		(pad "1" smd circle
			(at -0.40005 0)
			(size 0 0)
			(layers "F.Cu" "F.Mask" "F.Paste")
			(net "SMB_S3M_CPU0_3V3AUX_SCL_R")
		)
		(pad "2" smd circle
			(at 0.40005 0)
			(size 0 0)
			(layers "F.Cu" "F.Mask" "F.Paste")
			(net "SMB_S3M_CPU0_3V3AUX_SCL")
		)
	)
	(footprint ""
		(layer "F.Cu")
		(at 214.43188 -47.335948 90)
		(property "Reference" "R3588"
			(at 0 0 90)
			(layer "F.SilkS")
			(hide yes)
			(effects
				(font
					(size 1.27 1.27)
				)
			)
		)
		(property "Value" ""
			(at 0 0 90)
			(layer "F.Fab")
			(effects
				(font
					(size 1.27 1.27)
				)
			)
		)
		(duplicate_pad_numbers_are_jumpers no)
		(fp_line
			(start 0.7874 -0.4064)
			(end 0.7874 0.4064)
			(stroke
				(width 0.1524)
				(type default)
			)
			(layer "F.SilkS")
		)
		(fp_line
			(start -0.7874 -0.4064)
			(end 0.7874 -0.4064)
			(stroke
				(width 0.1524)
				(type default)
			)
			(layer "F.SilkS")
		)
		(fp_line
			(start 0.7874 0.4064)
			(end -0.7874 0.4064)
			(stroke
				(width 0.1524)
				(type default)
			)
			(layer "F.SilkS")
		)
		(fp_line
			(start -0.7874 0.4064)
			(end -0.7874 -0.4064)
			(stroke
				(width 0.1524)
				(type default)
			)
			(layer "F.SilkS")
		)
		(fp_line
			(start -0.12065 -0.305054)
			(end -0.12065 -0.2794)
			(stroke
				(width 0.1)
				(type default)
			)
			(layer "F.Fab")
		)
		(fp_line
			(start -0.67945 -0.305054)
			(end -0.12065 -0.305054)
			(stroke
				(width 0.1)
				(type default)
			)
			(layer "F.Fab")
		)
		(fp_line
			(start 0.67945 -0.3048)
			(end 0.67945 0.3048)
			(stroke
				(width 0.1)
				(type default)
			)
			(layer "F.Fab")
		)
		(fp_line
			(start 0.12065 -0.3048)
			(end 0.67945 -0.3048)
			(stroke
				(width 0.1)
				(type default)
			)
			(layer "F.Fab")
		)
		(fp_line
			(start 0.12065 -0.2794)
			(end 0.12065 -0.3048)
			(stroke
				(width 0.1)
				(type default)
			)
			(layer "F.Fab")
		)
		(fp_line
			(start -0.12065 -0.2794)
			(end 0.12065 -0.2794)
			(stroke
				(width 0.1)
				(type default)
			)
			(layer "F.Fab")
		)
		(fp_line
			(start 0.120396 0.2794)
			(end -0.12065 0.2794)
			(stroke
				(width 0.1)
				(type default)
			)
			(layer "F.Fab")
		)
		(fp_line
			(start -0.12065 0.2794)
			(end -0.12065 0.3048)
			(stroke
				(width 0.1)
				(type default)
			)
			(layer "F.Fab")
		)
		(fp_line
			(start 0.67945 0.3048)
			(end 0.120396 0.3048)
			(stroke
				(width 0.1)
				(type default)
			)
			(layer "F.Fab")
		)
		(fp_line
			(start 0.120396 0.3048)
			(end 0.120396 0.2794)
			(stroke
				(width 0.1)
				(type default)
			)
			(layer "F.Fab")
		)
		(fp_line
			(start -0.12065 0.3048)
			(end -0.67945 0.3048)
			(stroke
				(width 0.1)
				(type default)
			)
			(layer "F.Fab")
		)
		(fp_line
			(start -0.67945 0.3048)
			(end -0.67945 -0.305054)
			(stroke
				(width 0.1)
				(type default)
			)
			(layer "F.Fab")
		)
		(pad "1" smd circle
			(at -0.40005 0 90)
			(size 0 0)
			(layers "F.Cu" "F.Mask" "F.Paste")
			(net "SMB_INA230_3V3AUX_SCL")
		)
		(pad "2" smd circle
			(at 0.40005 0 90)
			(size 0 0)
			(layers "F.Cu" "F.Mask" "F.Paste")
			(net "SMB_INA230_2_3V3AUX_SCL_R")
		)
	)
)
